(kicad_pcb
	(version 20241229)
	(generator "pcbnew")
	(generator_version "9.0")
	(general
		(thickness 1.61)
		(legacy_teardrops no)
	)
	(paper "A3")
	(title_block
		(title "RDIMM DDR5 Tester")
		(date "2026-05-21")
		(rev "2.2.0")
		(company "Antmicro")
		(comment 9 "footprints 332-336 of 796")
	)
	(layers
		(0 "F.Cu" signal)
		(4 "In1.Cu" power)
		(6 "In2.Cu" mixed)
		(8 "In3.Cu" power)
		(10 "In4.Cu" mixed)
		(12 "In5.Cu" power)
		(14 "In6.Cu" mixed)
		(16 "In7.Cu" power)
		(18 "In8.Cu" power)
		(20 "In9.Cu" mixed)
		(22 "In10.Cu" power)
		(2 "B.Cu" signal)
		(9 "F.Adhes" user "F.Adhesive")
		(11 "B.Adhes" user "B.Adhesive")
		(13 "F.Paste" user)
		(15 "B.Paste" user)
		(5 "F.SilkS" user "F.Silkscreen")
		(7 "B.SilkS" user "B.Silkscreen")
		(1 "F.Mask" user)
		(3 "B.Mask" user)
		(17 "Dwgs.User" user "User.Drawings")
		(19 "Cmts.User" user "User.Comments")
		(21 "Eco1.User" user "User.Eco1")
		(23 "Eco2.User" user "User.Eco2")
		(25 "Edge.Cuts" user)
		(27 "Margin" user)
		(31 "F.CrtYd" user "F.Courtyard")
		(29 "B.CrtYd" user "B.Courtyard")
		(35 "F.Fab" user)
		(33 "B.Fab" user)
	)
	(footprint "antmicro-footprints:NetTie-2_SMD_Pad0.127mm"
		(layer "F.Cu")
		(at 256.113 148.15 180)
		(descr "Net tie, 2 pin, 0.127mm  SMD pads")
		(tags "net tie")
		(property "Reference" "NT15"
			(at -0.128 -1.345 0)
			(layer "F.SilkS")
			(hide yes)
			(effects
				(font
					(size 0.7 0.7)
					(thickness 0.15)
				)
				(justify right bottom)
			)
		)
		(property "Value" "Net-Tie_P0.127mm"
			(at 0 1.199 0)
			(layer "F.Fab")
			(effects
				(font
					(size 0.7 0.7)
					(thickness 0.15)
				)
				(justify right bottom)
			)
		)
		(property "MPN" ""
			(at 0 0 180)
			(unlocked yes)
			(layer "F.Fab")
			(hide yes)
			(effects
				(font
					(size 1 1)
					(thickness 0.15)
				)
			)
		)
		(property "Manufacturer" ""
			(at 0 0 180)
			(unlocked yes)
			(layer "F.Fab")
			(hide yes)
			(effects
				(font
					(size 1 1)
					(thickness 0.15)
				)
			)
		)
		(property "Author" "Antmicro"
			(at 0 0 180)
			(unlocked yes)
			(layer "F.Fab")
			(hide yes)
			(effects
				(font
					(size 1 1)
					(thickness 0.15)
				)
			)
		)
		(property "License" "Apache-2.0"
			(at 0 0 180)
			(unlocked yes)
			(layer "F.Fab")
			(hide yes)
			(effects
				(font
					(size 1 1)
					(thickness 0.15)
				)
			)
		)
		(property ki_fp_filters "Net*Tie*")
		(sheetname "/Supply/DC-DC IO/")
		(sheetfile "dc-dc-io.kicad_sch")
		(attr through_hole exclude_from_pos_files exclude_from_bom)
		(net_tie_pad_groups "1, 2")
		(fp_poly
			(pts
				(xy -0.0635 -0.0635) (xy 0.0625 -0.0635) (xy 0.0625 0.0635) (xy -0.0635 0.0635)
			)
			(stroke
				(width 0)
				(type solid)
			)
			(fill yes)
			(layer "F.Cu")
		)
		(fp_poly
			(pts
				(xy 0.2 -0.16) (xy 0.29 -0.07) (xy 0.29 0.07) (xy 0.2 0.16) (xy -0.2 0.16) (xy -0.29 0.07) (xy -0.29 -0.06)
				(xy -0.19 -0.16)
			)
			(stroke
				(width 0.05)
				(type solid)
			)
			(fill no)
			(layer "F.CrtYd")
		)
		(fp_text user "Author: Antmicro"
			(at -0.128 4.4 180)
			(layer "F.Fab")
			(effects
				(font
					(size 0.7 0.7)
					(thickness 0.15)
				)
				(justify left bottom)
			)
		)
		(fp_text user "${REFERENCE}"
			(at -0.128 3.2 180)
			(layer "F.Fab")
			(effects
				(font
					(size 0.7 0.7)
					(thickness 0.15)
				)
				(justify left bottom)
			)
		)
		(fp_text user "License: Apache-2.0"
			(at -0.128 5.6 180)
			(layer "F.Fab")
			(effects
				(font
					(size 0.7 0.7)
					(thickness 0.15)
				)
				(justify left bottom)
			)
		)
		(pad "1" smd roundrect
			(at -0.127 0)
			(size 0.127 0.127)
			(layers "F.Cu")
			(roundrect_rratio 0.5)
			(chamfer_ratio 0)
			(chamfer top_left bottom_left)
			(net 819 "/Supply/DC-DC IO/VDDQ_SEN_-")
			(pinfunction "1")
			(pintype "passive")
		)
		(pad "2" smd roundrect
			(at 0.126 0 180)
			(size 0.127 0.127)
			(layers "F.Cu")
			(roundrect_rratio 0.5)
			(chamfer_ratio 0)
			(chamfer top_left bottom_left)
			(net 687 "VDDQ")
			(pinfunction "2")
			(pintype "passive")
		)
	)
	(footprint "antmicro-footprints:C_0402_1005Metric"
		(layer "F.Cu")
		(at 256.825 128.925 90)
		(descr "Capacitor SMD 0402")
		(tags "capacitor SMD 0402")
		(property "Reference" "C194"
			(at -1.225 1.475 90)
			(layer "F.SilkS")
			(effects
				(font
					(size 0.7 0.7)
					(thickness 0.15)
				)
				(justify left bottom)
			)
		)
		(property "Value" "C_1u_0402"
			(at -1.022927 2.155213 90)
			(layer "F.Fab")
			(effects
				(font
					(size 0.7 0.7)
					(thickness 0.15)
				)
				(justify left bottom)
			)
		)
		(property "Datasheet" "https://product.tdk.com/en/search/capacitor/ceramic/mlcc/info?part_no=C1005X6S1A105K050BC"
			(at 0 0 90)
			(layer "F.Fab")
			(hide yes)
			(effects
				(font
					(size 1.27 1.27)
					(thickness 0.15)
				)
			)
		)
		(property "Manufacturer" "TDK"
			(at 0 0 90)
			(unlocked yes)
			(layer "F.Fab")
			(hide yes)
			(effects
				(font
					(size 1 1)
					(thickness 0.15)
				)
			)
		)
		(property "MPN" "C1005X6S1A105K050BC"
			(at 0 0 90)
			(unlocked yes)
			(layer "F.Fab")
			(hide yes)
			(effects
				(font
					(size 1 1)
					(thickness 0.15)
				)
			)
		)
		(property "Val" "1u"
			(at 0 0 90)
			(unlocked yes)
			(layer "F.Fab")
			(hide yes)
			(effects
				(font
					(size 1 1)
					(thickness 0.15)
				)
			)
		)
		(property "License" "Apache-2.0"
			(at 0 0 90)
			(unlocked yes)
			(layer "F.Fab")
			(hide yes)
			(effects
				(font
					(size 1 1)
					(thickness 0.15)
				)
			)
		)
		(property "Author" "Antmicro"
			(at 0 0 90)
			(unlocked yes)
			(layer "F.Fab")
			(hide yes)
			(effects
				(font
					(size 1 1)
					(thickness 0.15)
				)
			)
		)
		(property "Voltage" ""
			(at 0 0 90)
			(unlocked yes)
			(layer "F.Fab")
			(hide yes)
			(effects
				(font
					(size 1 1)
					(thickness 0.15)
				)
			)
		)
		(property "Dielectric" ""
			(at 0 0 90)
			(unlocked yes)
			(layer "F.Fab")
			(hide yes)
			(effects
				(font
					(size 1 1)
					(thickness 0.15)
				)
			)
		)
		(sheetname "/Supply/")
		(sheetfile "supply.kicad_sch")
		(attr smd)
		(fp_rect
			(start -0.925 -0.47)
			(end 0.925 0.47)
			(stroke
				(width 0.05)
				(type default)
			)
			(fill no)
			(layer "F.CrtYd")
		)
		(fp_line
			(start 0.504 -0.25)
			(end 0.504 0.248)
			(stroke
				(width 0.15)
				(type solid)
			)
			(layer "F.Fab")
		)
		(fp_line
			(start -0.494 -0.25)
			(end 0.504 -0.25)
			(stroke
				(width 0.15)
				(type solid)
			)
			(layer "F.Fab")
		)
		(fp_line
			(start 0.504 0.248)
			(end -0.494 0.248)
			(stroke
				(width 0.15)
				(type solid)
			)
			(layer "F.Fab")
		)
		(fp_line
			(start -0.494 0.248)
			(end -0.494 -0.25)
			(stroke
				(width 0.15)
				(type solid)
			)
			(layer "F.Fab")
		)
		(fp_text user "${REFERENCE}"
			(at -0.939 4.599 90)
			(layer "F.Fab")
			(effects
				(font
					(size 0.7 0.7)
					(thickness 0.15)
				)
				(justify left bottom)
			)
		)
		(fp_text user "Author: Antmicro"
			(at -0.939 3.399 90)
			(layer "F.Fab")
			(effects
				(font
					(size 0.7 0.7)
					(thickness 0.15)
				)
				(justify left bottom)
			)
		)
		(fp_text user "License: Apache-2.0"
			(at -0.939 5.799 90)
			(layer "F.Fab")
			(effects
				(font
					(size 0.7 0.7)
					(thickness 0.15)
				)
				(justify left bottom)
			)
		)
		(pad "1" smd roundrect
			(at -0.48 0 90)
			(size 0.59 0.64)
			(layers "F.Cu" "F.Mask" "F.Paste")
			(roundrect_rratio 0.25)
			(net 1 "GND")
			(pintype "passive")
		)
		(pad "2" smd roundrect
			(at 0.48 0 90)
			(size 0.59 0.64)
			(layers "F.Cu" "F.Mask" "F.Paste")
			(roundrect_rratio 0.25)
			(net 38 "+3V3_AON")
			(pintype "passive")
		)
	)
	(footprint "antmicro-footprints:C_Pol_EIA-D"
		(layer "F.Cu")
		(at 211.600002 160.4 90)
		(property "Reference" "C32"
			(at -6 2.434998 90)
			(layer "F.SilkS")
			(effects
				(font
					(size 0.7 0.7)
					(thickness 0.15)
				)
				(justify left bottom)
			)
		)
		(property "Value" "C_Pol_1m_2.5V_KEMET-T520-D"
			(at 0 3.4 90)
			(layer "F.Fab")
			(effects
				(font
					(size 0.7 0.7)
					(thickness 0.15)
				)
				(justify left bottom)
			)
		)
		(property "Datasheet" "https://www.kemet.com/en/us/capacitors/product/T520D108M2R5ATE030.html"
			(at 0 0 90)
			(layer "F.Fab")
			(hide yes)
			(effects
				(font
					(size 1.27 1.27)
					(thickness 0.15)
				)
			)
		)
		(property "MPN" "T520D108M2R5ATE030"
			(at 0 0 90)
			(unlocked yes)
			(layer "F.Fab")
			(hide yes)
			(effects
				(font
					(size 1 1)
					(thickness 0.15)
				)
			)
		)
		(property "Manufacturer" "KEMET"
			(at 0 0 90)
			(unlocked yes)
			(layer "F.Fab")
			(hide yes)
			(effects
				(font
					(size 1 1)
					(thickness 0.15)
				)
			)
		)
		(property "License" "Apache-2.0"
			(at 0 0 90)
			(unlocked yes)
			(layer "F.Fab")
			(hide yes)
			(effects
				(font
					(size 1 1)
					(thickness 0.15)
				)
			)
		)
		(property "Author" "Antmicro"
			(at 0 0 90)
			(unlocked yes)
			(layer "F.Fab")
			(hide yes)
			(effects
				(font
					(size 1 1)
					(thickness 0.15)
				)
			)
		)
		(property "Val" "1000u"
			(at 0 0 90)
			(unlocked yes)
			(layer "F.Fab")
			(hide yes)
			(effects
				(font
					(size 1 1)
					(thickness 0.15)
				)
			)
		)
		(property "Voltage" "2.5V"
			(at 0 0 90)
			(unlocked yes)
			(layer "F.Fab")
			(hide yes)
			(effects
				(font
					(size 1 1)
					(thickness 0.15)
				)
			)
		)
		(property "Dielectric" "template_dielectric"
			(at 0 0 90)
			(unlocked yes)
			(layer "F.Fab")
			(hide yes)
			(effects
				(font
					(size 1 1)
					(thickness 0.15)
				)
			)
		)
		(sheetname "/FPGA power/")
		(sheetfile "fpga-power.kicad_sch")
		(attr smd)
		(fp_line
			(start 3.6 -2.2)
			(end 3.6 -1.6)
			(stroke
				(width 0.15)
				(type solid)
			)
			(layer "F.SilkS")
		)
		(fp_line
			(start -3.58 -2.2)
			(end 3.6 -2.2)
			(stroke
				(width 0.15)
				(type solid)
			)
			(layer "F.SilkS")
		)
		(fp_line
			(start -4.1 -2.025)
			(end -4.1 -1.625)
			(stroke
				(width 0.12)
				(type solid)
			)
			(layer "F.SilkS")
		)
		(fp_line
			(start -4.3 -1.825)
			(end -3.9 -1.825)
			(stroke
				(width 0.12)
				(type solid)
			)
			(layer "F.SilkS")
		)
		(fp_line
			(start -3.58 -1.6)
			(end -3.58 -2.2)
			(stroke
				(width 0.15)
				(type solid)
			)
			(layer "F.SilkS")
		)
		(fp_line
			(start 3.6 1.6)
			(end 3.6 2.2)
			(stroke
				(width 0.15)
				(type solid)
			)
			(layer "F.SilkS")
		)
		(fp_line
			(start 3.6 2.2)
			(end -3.58 2.2)
			(stroke
				(width 0.15)
				(type solid)
			)
			(layer "F.SilkS")
		)
		(fp_line
			(start -3.58 2.2)
			(end -3.58 1.6)
			(stroke
				(width 0.15)
				(type solid)
			)
			(layer "F.SilkS")
		)
		(fp_line
			(start 3.77 -2.4)
			(end 3.77 -1.51)
			(stroke
				(width 0.05)
				(type solid)
			)
			(layer "F.CrtYd")
		)
		(fp_line
			(start -3.775 -2.4)
			(end 3.77 -2.4)
			(stroke
				(width 0.05)
				(type solid)
			)
			(layer "F.CrtYd")
		)
		(fp_line
			(start -3.775 -2.4)
			(end -3.775 -1.5)
			(stroke
				(width 0.05)
				(type solid)
			)
			(layer "F.CrtYd")
		)
		(fp_line
			(start 4.505 -1.51)
			(end 4.505 1.5)
			(stroke
				(width 0.05)
				(type solid)
			)
			(layer "F.CrtYd")
		)
		(fp_line
			(start 3.77 -1.51)
			(end 4.505 -1.51)
			(stroke
				(width 0.05)
				(type solid)
			)
			(layer "F.CrtYd")
		)
		(fp_line
			(start -3.775 -1.5)
			(end -4.505 -1.5)
			(stroke
				(width 0.05)
				(type solid)
			)
			(layer "F.CrtYd")
		)
		(fp_line
			(start 4.505 1.51)
			(end 3.77 1.51)
			(stroke
				(width 0.05)
				(type solid)
			)
			(layer "F.CrtYd")
		)
		(fp_line
			(start 3.77 1.51)
			(end 3.77 2.4)
			(stroke
				(width 0.05)
				(type solid)
			)
			(layer "F.CrtYd")
		)
		(fp_line
			(start -3.77 1.51)
			(end -4.505 1.51)
			(stroke
				(width 0.05)
				(type solid)
			)
			(layer "F.CrtYd")
		)
		(fp_line
			(start -4.505 1.51)
			(end -4.505 -1.5)
			(stroke
				(width 0.05)
				(type solid)
			)
			(layer "F.CrtYd")
		)
		(fp_line
			(start 3.77 2.4)
			(end -3.77 2.4)
			(stroke
				(width 0.05)
				(type solid)
			)
			(layer "F.CrtYd")
		)
		(fp_line
			(start -3.77 2.4)
			(end -3.77 1.51)
			(stroke
				(width 0.05)
				(type solid)
			)
			(layer "F.CrtYd")
		)
		(fp_rect
			(start -3.65 -2.15)
			(end 3.65 2.15)
			(stroke
				(width 0.15)
				(type solid)
			)
			(fill no)
			(layer "F.Fab")
		)
		(fp_text user "License: Apache-2.0"
			(at -4.5 6.6 90)
			(layer "F.Fab")
			(effects
				(font
					(size 0.7 0.7)
					(thickness 0.15)
				)
				(justify left bottom)
			)
		)
		(fp_text user "${REFERENCE}"
			(at -4.5 5.6 90)
			(layer "F.Fab")
			(effects
				(font
					(size 0.7 0.7)
					(thickness 0.15)
				)
				(justify left bottom)
			)
		)
		(fp_text user "Author: Antmicro"
			(at -4.5 7.6 90)
			(layer "F.Fab")
			(effects
				(font
					(size 0.7 0.7)
					(thickness 0.15)
				)
				(justify left bottom)
			)
		)
		(pad "1" smd roundrect
			(at -3.1 0 90)
			(size 2.31 2.52)
			(layers "F.Cu" "F.Mask" "F.Paste")
			(roundrect_rratio 0.1)
			(net 553 "+0V85")
			(pintype "passive")
		)
		(pad "2" smd roundrect
			(at 3.1 0 90)
			(size 2.31 2.52)
			(layers "F.Cu" "F.Mask" "F.Paste")
			(roundrect_rratio 0.1)
			(net 1 "GND")
			(pintype "passive")
		)
	)
	(footprint "antmicro-footprints:R_0402_1005Metric"
		(layer "F.Cu")
		(at 108.324499 148.564 90)
		(descr "Resistor SMD 0402")
		(tags "resistor SMD 0402")
		(property "Reference" "R90"
			(at -3.186 0.425501 90)
			(layer "F.SilkS")
			(effects
				(font
					(size 0.7 0.7)
					(thickness 0.15)
				)
				(justify left bottom)
			)
		)
		(property "Value" "R_330R_0402"
			(at -1.011843 1.772047 90)
			(layer "F.Fab")
			(effects
				(font
					(size 0.7 0.7)
					(thickness 0.15)
				)
				(justify left bottom)
			)
		)
		(property "Datasheet" "https://www.bourns.com/docs/product-datasheets/cr.pdf"
			(at 0 0 90)
			(layer "F.Fab")
			(hide yes)
			(effects
				(font
					(size 1.27 1.27)
					(thickness 0.15)
				)
			)
		)
		(property "Manufacturer" "Bourns"
			(at 0 0 90)
			(unlocked yes)
			(layer "F.Fab")
			(hide yes)
			(effects
				(font
					(size 1 1)
					(thickness 0.15)
				)
			)
		)
		(property "MPN" "CR0402-FX-3300GLF"
			(at 0 0 90)
			(unlocked yes)
			(layer "F.Fab")
			(hide yes)
			(effects
				(font
					(size 1 1)
					(thickness 0.15)
				)
			)
		)
		(property "Val" "330R"
			(at 0 0 90)
			(unlocked yes)
			(layer "F.Fab")
			(hide yes)
			(effects
				(font
					(size 1 1)
					(thickness 0.15)
				)
			)
		)
		(property "License" "Apache-2.0"
			(at 0 0 90)
			(unlocked yes)
			(layer "F.Fab")
			(hide yes)
			(effects
				(font
					(size 1 1)
					(thickness 0.15)
				)
			)
		)
		(property "Author" "Antmicro"
			(at 0 0 90)
			(unlocked yes)
			(layer "F.Fab")
			(hide yes)
			(effects
				(font
					(size 1 1)
					(thickness 0.15)
				)
			)
		)
		(property "Tolerance" "1%"
			(at 0 0 90)
			(unlocked yes)
			(layer "F.Fab")
			(hide yes)
			(effects
				(font
					(size 1 1)
					(thickness 0.15)
				)
			)
		)
		(sheetname "/Debug FTDI + VNA/")
		(sheetfile "debug-ftdi.kicad_sch")
		(attr smd)
		(fp_rect
			(start -0.925 -0.47)
			(end 0.925 0.47)
			(stroke
				(width 0.05)
				(type default)
			)
			(fill no)
			(layer "F.CrtYd")
		)
		(fp_rect
			(start -0.5 -0.25)
			(end 0.5 0.25)
			(stroke
				(width 0.15)
				(type solid)
			)
			(fill no)
			(layer "F.Fab")
		)
		(fp_text user "Author: Antmicro"
			(at -0.95 4.169 90)
			(layer "F.Fab")
			(effects
				(font
					(size 0.7 0.7)
					(thickness 0.15)
				)
				(justify left bottom)
			)
		)
		(fp_text user "${REFERENCE}"
			(at -0.95 3.168 90)
			(layer "F.Fab")
			(effects
				(font
					(size 0.7 0.7)
					(thickness 0.15)
				)
				(justify left bottom)
			)
		)
		(fp_text user "License: Apache-2.0"
			(at -0.95 5.169 90)
			(layer "F.Fab")
			(effects
				(font
					(size 0.7 0.7)
					(thickness 0.15)
				)
				(justify left bottom)
			)
		)
		(pad "1" smd roundrect
			(at -0.48 0 90)
			(size 0.59 0.64)
			(layers "F.Cu" "F.Mask" "F.Paste")
			(roundrect_rratio 0.25)
			(net 1 "GND")
			(pintype "passive")
		)
		(pad "2" smd roundrect
			(at 0.48 0 90)
			(size 0.59 0.64)
			(layers "F.Cu" "F.Mask" "F.Paste")
			(roundrect_rratio 0.25)
			(net 321 "Net-(C133-Pad1)")
			(pintype "passive")
		)
	)
	(footprint "antmicro-footprints:C_0402_1005Metric"
		(layer "F.Cu")
		(at 150.375499 171.167 90)
		(descr "Capacitor SMD 0402")
		(tags "capacitor SMD 0402")
		(property "Reference" "C131"
			(at -1.213 1.954501 90)
			(layer "F.SilkS")
			(effects
				(font
					(size 0.7 0.7)
					(thickness 0.15)
				)
				(justify left bottom)
			)
		)
		(property "Value" "C_100n_0402"
			(at -1.022927 2.155213 90)
			(layer "F.Fab")
			(effects
				(font
					(size 0.7 0.7)
					(thickness 0.15)
				)
				(justify left bottom)
			)
		)
		(property "Datasheet" "https://www.murata.com/products/productdetail?partno=GRM155R61H104KE14%23"
			(at 0 0 90)
			(layer "F.Fab")
			(hide yes)
			(effects
				(font
					(size 1.27 1.27)
					(thickness 0.15)
				)
			)
		)
		(property "MPN" "GRM155R61H104KE14D"
			(at 0 0 90)
			(unlocked yes)
			(layer "F.Fab")
			(hide yes)
			(effects
				(font
					(size 1 1)
					(thickness 0.15)
				)
			)
		)
		(property "Manufacturer" "Murata"
			(at 0 0 90)
			(unlocked yes)
			(layer "F.Fab")
			(hide yes)
			(effects
				(font
					(size 1 1)
					(thickness 0.15)
				)
			)
		)
		(property "License" "Apache-2.0"
			(at 0 0 90)
			(unlocked yes)
			(layer "F.Fab")
			(hide yes)
			(effects
				(font
					(size 1 1)
					(thickness 0.15)
				)
			)
		)
		(property "Author" "Antmicro"
			(at 0 0 90)
			(unlocked yes)
			(layer "F.Fab")
			(hide yes)
			(effects
				(font
					(size 1 1)
					(thickness 0.15)
				)
			)
		)
		(property "Val" "100n"
			(at 0 0 90)
			(unlocked yes)
			(layer "F.Fab")
			(hide yes)
			(effects
				(font
					(size 1 1)
					(thickness 0.15)
				)
			)
		)
		(property "Voltage" "50V"
			(at 0 0 90)
			(unlocked yes)
			(layer "F.Fab")
			(hide yes)
			(effects
				(font
					(size 1 1)
					(thickness 0.15)
				)
			)
		)
		(property "Dielectric" "X5R"
			(at 0 0 90)
			(unlocked yes)
			(layer "F.Fab")
			(hide yes)
			(effects
				(font
					(size 1 1)
					(thickness 0.15)
				)
			)
		)
		(sheetname "/Debug FTDI + VNA/")
		(sheetfile "debug-ftdi.kicad_sch")
		(attr smd)
		(fp_rect
			(start -0.925 -0.47)
			(end 0.925 0.47)
			(stroke
				(width 0.05)
				(type default)
			)
			(fill no)
			(layer "F.CrtYd")
		)
		(fp_line
			(start 0.504 -0.25)
			(end 0.504 0.248)
			(stroke
				(width 0.15)
				(type solid)
			)
			(layer "F.Fab")
		)
		(fp_line
			(start -0.494 -0.25)
			(end 0.504 -0.25)
			(stroke
				(width 0.15)
				(type solid)
			)
			(layer "F.Fab")
		)
		(fp_line
			(start 0.504 0.248)
			(end -0.494 0.248)
			(stroke
				(width 0.15)
				(type solid)
			)
			(layer "F.Fab")
		)
		(fp_line
			(start -0.494 0.248)
			(end -0.494 -0.25)
			(stroke
				(width 0.15)
				(type solid)
			)
			(layer "F.Fab")
		)
		(fp_text user "License: Apache-2.0"
			(at -0.939 5.799 90)
			(layer "F.Fab")
			(effects
				(font
					(size 0.7 0.7)
					(thickness 0.15)
				)
				(justify left bottom)
			)
		)
		(fp_text user "${REFERENCE}"
			(at -0.939 4.599 90)
			(layer "F.Fab")
			(effects
				(font
					(size 0.7 0.7)
					(thickness 0.15)
				)
				(justify left bottom)
			)
		)
		(fp_text user "Author: Antmicro"
			(at -0.939 3.399 90)
			(layer "F.Fab")
			(effects
				(font
					(size 0.7 0.7)
					(thickness 0.15)
				)
				(justify left bottom)
			)
		)
		(pad "1" smd roundrect
			(at -0.48 0 90)
			(size 0.59 0.64)
			(layers "F.Cu" "F.Mask" "F.Paste")
			(roundrect_rratio 0.25)
			(net 1 "GND")
			(pintype "passive")
		)
		(pad "2" smd roundrect
			(at 0.48 0 90)
			(size 0.59 0.64)
			(layers "F.Cu" "F.Mask" "F.Paste")
			(roundrect_rratio 0.25)
			(net 38 "+3V3_AON")
			(pintype "passive")
		)
	)
)
